(kicad_pcb
	(version 20221018)
	(generator pcbnew)
	(general
    (thickness 1.562)
  )
	(paper "A4")
	(title_block
    (title "Thunderbolt PCIe Adaper")
    (date "2024-07-09")
    (rev "1.0.3")
    (comment 1 "www.antmicro.com")
    (comment 2 "Antmicro Ltd.")
		(comment 9 "footprint 10 of 271 (U4), pads 294-337 of 337")
	)
	(layers
    (0 "F.Cu" signal)
    (1 "In1.Cu" signal)
    (2 "In2.Cu" signal)
    (3 "In3.Cu" signal)
    (4 "In4.Cu" signal)
    (31 "B.Cu" signal)
    (32 "B.Adhes" user "B.Adhesive")
    (33 "F.Adhes" user "F.Adhesive")
    (34 "B.Paste" user)
    (35 "F.Paste" user)
    (36 "B.SilkS" user "B.Silkscreen")
    (37 "F.SilkS" user "F.Silkscreen")
    (38 "B.Mask" user)
    (39 "F.Mask" user)
    (40 "Dwgs.User" user "User.Drawings")
    (41 "Cmts.User" user "User.Comments")
    (42 "Eco1.User" user "User.Eco1")
    (43 "Eco2.User" user "User.Eco2")
    (44 "Edge.Cuts" user)
    (45 "Margin" user)
    (46 "B.CrtYd" user "B.Courtyard")
    (47 "F.CrtYd" user "F.Courtyard")
    (48 "B.Fab" user)
    (49 "F.Fab" user)
  )
	(footprint "antmicro-footprints:JHL6340SLLSQ"
    (layer "F.Cu")
    (at 134.8 79.85 -90)
    (property "Author" "Antmicro")
    (property "License" "Apache-2.0")
    (property "MPN" "JHL6340SLLSQ")
    (property "Manufacturer" "Intel")
    (property "Sheetfile" "tb-power.kicad_sch")
    (property "Sheetname" "Thunderbolt Controller - Power")
    (property "ki_description" "Thunderbolt™ 3 Controller, I/O")
    (property "ki_keywords" "IC")
    (attr smd)
    (fp_text reference "U4" (at -4.666 -6.17 -90 unlocked) (layer "F.SilkS")
        (effects (font (size 0.7 0.7) (thickness 0.15)))
    )
    (fp_text value "JHL6340SLLSQ" (at 0 6.4 -90 unlocked) (layer "F.Fab")
        (effects (font (size 0.7 0.7) (thickness 0.15)))
    )
    (pad "V11" smd circle (at -0.65 2.6 270) (size 0.254 0.254) (layers "F.Cu" "F.Paste" "F.Mask")
      (net 106 "Net-(C53-Pad2)") (pinfunction "VCC0P9_ANA_DPSNK") (pintype "power_in"))
    (pad "V12" smd circle (at 0 2.6 270) (size 0.254 0.254) (layers "F.Cu" "F.Paste" "F.Mask")
      (net 106 "Net-(C53-Pad2)") (pinfunction "VCC0P9_ANA_DPSNK") (pintype "passive"))
    (pad "V13" smd circle (at 0.65 2.6 270) (size 0.254 0.254) (layers "F.Cu" "F.Paste" "F.Mask")
      (net 106 "Net-(C53-Pad2)") (pinfunction "VCC0P9_ANA_DPSNK") (pintype "passive"))
    (pad "V15" smd circle (at 1.3 2.6 270) (size 0.254 0.254) (layers "F.Cu" "F.Paste" "F.Mask")
      (net 1 "GND") (pinfunction "VSS_ANA") (pintype "passive"))
    (pad "V16" smd circle (at 1.95 2.6 270) (size 0.254 0.254) (layers "F.Cu" "F.Paste" "F.Mask")
      (net 1 "GND") (pinfunction "VSS_ANA") (pintype "passive"))
    (pad "V18" smd circle (at 2.6 2.6 270) (size 0.254 0.254) (layers "F.Cu" "F.Paste" "F.Mask")
      (net 259 "unconnected-(U4F-PCIE_ATEST-PadV18)") (pinfunction "PCIE_ATEST") (pintype "passive+no_connect"))
    (pad "V19" smd circle (at 3.25 2.6 270) (size 0.254 0.254) (layers "F.Cu" "F.Paste" "F.Mask")
      (net 72 "/TB Controller/PCIE_CLK_JHL_P") (pinfunction "PCIE_REFCLK_100_IN_P") (pintype "input"))
    (pad "V20" smd circle (at 3.9 2.6 270) (size 0.254 0.254) (layers "F.Cu" "F.Paste" "F.Mask")
      (net 1 "GND") (pinfunction "VSS_ANA") (pintype "passive"))
    (pad "V22" smd circle (at 4.6 2.76 270) (size 0.254 0.254) (layers "F.Cu" "F.Paste" "F.Mask")
      (net 76 "/TB Controller/TX0_N") (pinfunction "PCIE_TX0_N") (pintype "input"))
    (pad "V23" smd oval (at 5.06 2.76) (size 0.1578 0.3302) (layers "F.Cu" "F.Paste" "F.Mask")
      (net 80 "/TB Controller/TX0_P") (pinfunction "PCIE_TX0_P") (pintype "input"))
    (pad "W1" smd oval (at -5.06 3.22) (size 0.1578 0.3302) (layers "F.Cu" "F.Paste" "F.Mask")
      (net 193 "Net-(U4C-GPIO_4)") (pinfunction "GPIO_4") (pintype "bidirectional"))
    (pad "W2" smd circle (at -4.6 3.22 270) (size 0.254 0.254) (layers "F.Cu" "F.Paste" "F.Mask")
      (net 194 "Net-(U4C-GPIO_5)") (pinfunction "GPIO_5") (pintype "bidirectional"))
    (pad "W4" smd circle (at -3.9 3.25 270) (size 0.254 0.254) (layers "F.Cu" "F.Paste" "F.Mask")
      (net 181 "Net-(U4D-TDO)") (pinfunction "TDO") (pintype "output"))
    (pad "W5" smd circle (at -3.25 3.25 270) (size 0.254 0.254) (layers "F.Cu" "F.Paste" "F.Mask")
      (net 1 "GND") (pinfunction "VSS_ANA") (pintype "passive"))
    (pad "W6" smd circle (at -2.6 3.25 270) (size 0.254 0.254) (layers "F.Cu" "F.Paste" "F.Mask")
      (net 1 "GND") (pinfunction "VSS_ANA") (pintype "passive"))
    (pad "W8" smd circle (at -1.95 3.25 270) (size 0.254 0.254) (layers "F.Cu" "F.Paste" "F.Mask")
      (net 1 "GND") (pinfunction "VSS_ANA") (pintype "passive"))
    (pad "W9" smd circle (at -1.3 3.25 270) (size 0.254 0.254) (layers "F.Cu" "F.Paste" "F.Mask")
      (net 1 "GND") (pinfunction "VSS_ANA") (pintype "passive"))
    (pad "W11" smd circle (at -0.65 3.25 270) (size 0.254 0.254) (layers "F.Cu" "F.Paste" "F.Mask")
      (net 260 "unconnected-(U4C-DPSNK0_AUX_N-PadW11)") (pinfunction "DPSNK0_AUX_N") (pintype "bidirectional+no_connect"))
    (pad "W12" smd circle (at 0 3.25 270) (size 0.254 0.254) (layers "F.Cu" "F.Paste" "F.Mask")
      (net 261 "unconnected-(U4C-DPSNK1_AUX_N-PadW12)") (pinfunction "DPSNK1_AUX_N") (pintype "bidirectional+no_connect"))
    (pad "W13" smd circle (at 0.65 3.25 270) (size 0.254 0.254) (layers "F.Cu" "F.Paste" "F.Mask")
      (net 1 "GND") (pinfunction "MONDC_DPSNK_0") (pintype "passive"))
    (pad "W15" smd circle (at 1.3 3.25 270) (size 0.254 0.254) (layers "F.Cu" "F.Paste" "F.Mask")
      (net 87 "/TB Controller/PA_AUX_N") (pinfunction "PA_DPSRC_AUX_N") (pintype "bidirectional"))
    (pad "W16" smd circle (at 1.95 3.25 270) (size 0.254 0.254) (layers "F.Cu" "F.Paste" "F.Mask")
      (net 262 "unconnected-(U4E-PB_DPSRC_AUX_N-PadW16)") (pinfunction "PB_DPSRC_AUX_N") (pintype "bidirectional+no_connect"))
    (pad "W18" smd circle (at 2.6 3.25 270) (size 0.254 0.254) (layers "F.Cu" "F.Paste" "F.Mask")
      (net 1 "GND") (pinfunction "MONDC_DPSNK_1") (pintype "passive"))
    (pad "W19" smd circle (at 3.25 3.25 270) (size 0.254 0.254) (layers "F.Cu" "F.Paste" "F.Mask")
      (net 263 "unconnected-(U4C-DPSRC_AUX_P-PadW19)") (pinfunction "DPSRC_AUX_P") (pintype "bidirectional+no_connect"))
    (pad "W20" smd circle (at 3.9 3.25 270) (size 0.254 0.254) (layers "F.Cu" "F.Paste" "F.Mask")
      (net 1 "GND") (pinfunction "VSS_ANA") (pintype "passive"))
    (pad "W22" smd circle (at 4.6 3.22 270) (size 0.254 0.254) (layers "F.Cu" "F.Paste" "F.Mask")
      (net 1 "GND") (pinfunction "VSS_ANA") (pintype "passive"))
    (pad "W23" smd oval (at 5.06 3.22) (size 0.1578 0.3302) (layers "F.Cu" "F.Paste" "F.Mask")
      (net 1 "GND") (pinfunction "VSS_ANA") (pintype "passive"))
    (pad "Y1" smd oval (at -5.06 3.68) (size 0.1578 0.3302) (layers "F.Cu" "F.Paste" "F.Mask")
      (net 195 "Net-(U4C-GPIO_6)") (pinfunction "GPIO_6") (pintype "bidirectional"))
    (pad "Y2" smd circle (at -4.6 3.68 270) (size 0.254 0.254) (layers "F.Cu" "F.Paste" "F.Mask")
      (net 196 "Net-(U4C-GPIO_7)") (pinfunction "GPIO_7") (pintype "bidirectional"))
    (pad "Y4" smd circle (at -3.9 3.9 270) (size 0.254 0.254) (layers "F.Cu" "F.Paste" "F.Mask")
      (net 178 "Net-(U4D-TDI)") (pinfunction "TDI") (pintype "input"))
    (pad "Y5" smd circle (at -3.25 3.9 270) (size 0.254 0.254) (layers "F.Cu" "F.Paste" "F.Mask")
      (net 172 "Net-(U4C-DPSNK0_DDC_CLK)") (pinfunction "DPSNK0_DDC_CLK") (pintype "passive"))
    (pad "Y6" smd circle (at -2.6 3.9 270) (size 0.254 0.254) (layers "F.Cu" "F.Paste" "F.Mask")
      (net 174 "Net-(U4C-DPSNK1_HPD)") (pinfunction "DPSNK1_HPD") (pintype "passive"))
    (pad "Y8" smd circle (at -1.95 3.9 270) (size 0.254 0.254) (layers "F.Cu" "F.Paste" "F.Mask")
      (net 175 "Net-(U4C-DPSNK1_DDC_CLK)") (pinfunction "DPSNK1_DDC_CLK") (pintype "passive"))
    (pad "Y9" smd circle (at -1.3 3.9 270) (size 0.254 0.254) (layers "F.Cu" "F.Paste" "F.Mask")
      (net 1 "GND") (pinfunction "VSS_ANA") (pintype "passive"))
    (pad "Y11" smd circle (at -0.65 3.9 270) (size 0.254 0.254) (layers "F.Cu" "F.Paste" "F.Mask")
      (net 264 "unconnected-(U4C-DPSNK0_AUXP-PadY11)") (pinfunction "DPSNK0_AUXP") (pintype "bidirectional+no_connect"))
    (pad "Y12" smd circle (at 0 3.9 270) (size 0.254 0.254) (layers "F.Cu" "F.Paste" "F.Mask")
      (net 265 "unconnected-(U4C-DPSNK1_AUXP-PadY12)") (pinfunction "DPSNK1_AUXP") (pintype "bidirectional+no_connect"))
    (pad "Y13" smd circle (at 0.65 3.9 270) (size 0.254 0.254) (layers "F.Cu" "F.Paste" "F.Mask")
      (net 1 "GND") (pinfunction "VSS_ANA") (pintype "passive"))
    (pad "Y15" smd circle (at 1.3 3.9 270) (size 0.254 0.254) (layers "F.Cu" "F.Paste" "F.Mask")
      (net 86 "/TB Controller/PA_AUX_P") (pinfunction "PA_DPSRC_AUX_P") (pintype "bidirectional"))
    (pad "Y16" smd circle (at 1.95 3.9 270) (size 0.254 0.254) (layers "F.Cu" "F.Paste" "F.Mask")
      (net 266 "unconnected-(U4E-PB_DPSRC_AUX_P-PadY16)") (pinfunction "PB_DPSRC_AUX_P") (pintype "bidirectional+no_connect"))
    (pad "Y18" smd circle (at 2.6 3.9 270) (size 0.254 0.254) (layers "F.Cu" "F.Paste" "F.Mask")
      (net 177 "Net-(U4C-DPSNK_RBIAS)") (pinfunction "DPSNK_RBIAS") (pintype "passive"))
    (pad "Y19" smd circle (at 3.25 3.9 270) (size 0.254 0.254) (layers "F.Cu" "F.Paste" "F.Mask")
      (net 267 "unconnected-(U4C-DPSRC_AUX_N-PadY19)") (pinfunction "DPSRC_AUX_N") (pintype "bidirectional+no_connect"))
    (pad "Y20" smd circle (at 3.9 3.9 270) (size 0.254 0.254) (layers "F.Cu" "F.Paste" "F.Mask")
      (net 1 "GND") (pinfunction "VSS_ANA") (pintype "passive"))
    (pad "Y22" smd circle (at 4.6 3.68 270) (size 0.254 0.254) (layers "F.Cu" "F.Paste" "F.Mask")
      (net 47 "PCIE_RX0_N") (pinfunction "PCIE_RX0_N") (pintype "input"))
    (pad "Y23" smd oval (at 5.06 3.68) (size 0.1578 0.3302) (layers "F.Cu" "F.Paste" "F.Mask")
      (net 46 "PCIE_RX0_P") (pinfunction "PCIE_RX0_P") (pintype "input"))
  )
)
